FILE_TYPE = CONNECTIVITY;
{Allegro Design Entry HDL 17.2-2016 S081 (4005846) 1/11/2022}
"PAGE_NUMBER" = 126;
0"NC";
1"PVNN_TERM_CPU0\g";
2"PVNN_TERM_CPU1\g";
3"PU_CPU0_UPI3_AC_COUPLING";
4"PU_CPU0_UPI0_AC_COUPLING";
5"PU_CPU0_UPI1_AC_COUPLING";
6"PU_CPU1_UPI3_AC_COUPLING";
7"PU_CPU1_UPI2_AC_COUPLING";
8"PU_CPU1_UPI1_AC_COUPLING";
9"PU_CPU1_UPI0_AC_COUPLING";
10"PU_CPU0_UPI2_AC_COUPLING";
%"Q_RES"
"1","(-1700,-150)","0","pure_quanta","I114";
;
PART_NUMBER"CS12402FB01"
WATTAGE"1/16W"
PACK_TYPE"0402LF"
VALUE"240"
MATERIAL"EMPTY"
TOLERANCE"1%"
$LOCATION"R97"
CDS_LIB"pure_quanta"
CDS_LOCATION"R97"
$SEC"1"
CDS_SEC"1";
"B"
$PN"2"3;
"A"
$PN"1"1;
%"Q_RES"
"1","(-1725,-1100)","0","pure_quanta","I135";
;
PART_NUMBER"CS12402FB01"
TOLERANCE"1%"
MATERIAL"EMPTY"
VALUE"240"
WATTAGE"1/16W"
PACK_TYPE"0402LF"
$LOCATION"R90"
CDS_LIB"pure_quanta"
CDS_LOCATION"R90"
$SEC"1"
CDS_SEC"1";
"B"
$PN"2"9;
"A"
$PN"1"2;
%"Q_RES"
"1","(-1725,-1225)","0","pure_quanta","I136";
;
PART_NUMBER"CS12402FB01"
PACK_TYPE"0402LF"
WATTAGE"1/16W"
VALUE"240"
TOLERANCE"1%"
MATERIAL"EMPTY"
$LOCATION"R91"
CDS_LIB"pure_quanta"
CDS_LOCATION"R91"
$SEC"1"
CDS_SEC"1";
"B"
$PN"2"8;
"A"
$PN"1"2;
%"UNIVERSAL_POWER"
"1","(-2075,-850)","0","logical_power","I137";
;
HDL_POWER"PVNN_TERM_CPU1"
CDS_LIB"logical_power";
"A"2;
%"Q_RES"
"1","(-1725,-1350)","0","pure_quanta","I140";
;
PART_NUMBER"CS12402FB01"
PACK_TYPE"0402LF"
WATTAGE"1/16W"
VALUE"240"
TOLERANCE"1%"
MATERIAL"EMPTY"
$LOCATION"R92"
CDS_LIB"pure_quanta"
CDS_LOCATION"R92"
$SEC"1"
CDS_SEC"1";
"B"
$PN"2"7;
"A"
$PN"1"2;
%"Q_RES"
"1","(-1725,-1475)","0","pure_quanta","I141";
;
PART_NUMBER"CS12402FB01"
PACK_TYPE"0402LF"
WATTAGE"1/16W"
VALUE"240"
MATERIAL"EMPTY"
TOLERANCE"1%"
$LOCATION"R93"
CDS_LIB"pure_quanta"
CDS_LOCATION"R93"
$SEC"1"
CDS_SEC"1";
"B"
$PN"2"6;
"A"
$PN"1"2;
%"Q_RES"
"1","(-1700,-25)","0","pure_quanta","I22";
;
PART_NUMBER"CS12402FB01"
VALUE"240"
TOLERANCE"1%"
PACK_TYPE"0402LF"
WATTAGE"1/16W"
MATERIAL"EMPTY"
$LOCATION"R96"
CDS_LIB"pure_quanta"
CDS_LOCATION"R96"
$SEC"1"
CDS_SEC"1";
"B"
$PN"2"10;
"A"
$PN"1"1;
%"Q_RES"
"1","(-1700,100)","0","pure_quanta","I23";
;
PART_NUMBER"CS12402FB01"
MATERIAL"EMPTY"
PACK_TYPE"0402LF"
TOLERANCE"1%"
VALUE"240"
WATTAGE"1/16W"
$LOCATION"R95"
CDS_LIB"pure_quanta"
CDS_LOCATION"R95"
$SEC"1"
CDS_SEC"1";
"B"
$PN"2"5;
"A"
$PN"1"1;
%"UNIVERSAL_POWER"
"1","(-2050,475)","0","logical_power","I24";
;
HDL_POWER"PVNN_TERM_CPU0"
CDS_LIB"logical_power";
"A"1;
%"Q_RES"
"1","(-1700,225)","0","pure_quanta","I25";
;
PART_NUMBER"CS12402FB01"
MATERIAL"EMPTY"
PACK_TYPE"0402LF"
TOLERANCE"1%"
VALUE"240"
WATTAGE"1/16W"
$LOCATION"R94"
CDS_LIB"pure_quanta"
CDS_LOCATION"R94"
$SEC"1"
CDS_SEC"1";
"B"
$PN"2"4;
"A"
$PN"1"1;
END.
